(kicad_pcb
	(version 20241229)
	(generator "pcbnew")
	(generator_version "9.0")
	(general
		(thickness 1.62)
		(legacy_teardrops no)
	)
	(paper "A3")
	(title_block
		(title "COM Express 7 Baseboard")
		(date "2025-02-04")
		(rev "1.1.2")
		(company "Antmicro Ltd")
		(comment 1 "www.antmicro.com")
		(comment 9 "footprints 658-659 of 802")
	)
	(layers
		(0 "F.Cu" signal)
		(4 "In1.Cu" signal)
		(6 "In2.Cu" signal)
		(8 "In3.Cu" signal)
		(10 "In4.Cu" signal)
		(12 "In5.Cu" signal)
		(14 "In6.Cu" signal)
		(2 "B.Cu" signal)
		(9 "F.Adhes" user "F.Adhesive")
		(11 "B.Adhes" user "B.Adhesive")
		(13 "F.Paste" user)
		(15 "B.Paste" user)
		(5 "F.SilkS" user "F.Silkscreen")
		(7 "B.SilkS" user "B.Silkscreen")
		(1 "F.Mask" user)
		(3 "B.Mask" user)
		(17 "Dwgs.User" user "User.Drawings")
		(19 "Cmts.User" user "User.Comments")
		(21 "Eco1.User" user "User.Eco1")
		(23 "Eco2.User" user "User.Eco2")
		(25 "Edge.Cuts" user)
		(27 "Margin" user)
		(31 "F.CrtYd" user "F.Courtyard")
		(29 "B.CrtYd" user "B.Courtyard")
		(35 "F.Fab" user)
		(33 "B.Fab" user)
	)
	(footprint "antmicro-footprints:C_0603_1608Metric"
		(layer "B.Cu")
		(at 218.15 128.85)
		(descr "Capacitor SMD 0603")
		(tags "capacitor 0603")
		(property "Reference" "C106"
			(at 1.15 0.81 0)
			(layer "B.SilkS")
			(effects
				(font
					(size 0.7 0.7)
					(thickness 0.15)
				)
				(justify right bottom mirror)
			)
		)
		(property "Value" "C_22u_16V_0603"
			(at -1.42757 -1.770288 0)
			(layer "B.Fab")
			(effects
				(font
					(size 0.7 0.7)
					(thickness 0.15)
				)
				(justify right bottom mirror)
			)
		)
		(property "Datasheet" "https://product.samsungsem.com/mlcc/CL10A226MO7JZN.do"
			(at 0 0 0)
			(layer "F.Fab")
			(hide yes)
			(effects
				(font
					(size 1.27 1.27)
					(thickness 0.15)
				)
			)
		)
		(property "Author" "Antmicro"
			(at 0 0 0)
			(layer "B.Fab")
			(hide yes)
			(effects
				(font
					(size 1 1)
					(thickness 0.15)
				)
				(justify mirror)
			)
		)
		(property "Dielectric" ""
			(at 0 0 0)
			(layer "B.Fab")
			(hide yes)
			(effects
				(font
					(size 1 1)
					(thickness 0.15)
				)
				(justify mirror)
			)
		)
		(property "License" "Apache-2.0"
			(at 0 0 0)
			(layer "B.Fab")
			(hide yes)
			(effects
				(font
					(size 1 1)
					(thickness 0.15)
				)
				(justify mirror)
			)
		)
		(property "MPN" "CL10A226MO7JZNC"
			(at 0 0 0)
			(layer "B.Fab")
			(hide yes)
			(effects
				(font
					(size 1 1)
					(thickness 0.15)
				)
				(justify mirror)
			)
		)
		(property "Manufacturer" "Samsung Electro-Mechanics"
			(at 0 0 0)
			(layer "B.Fab")
			(hide yes)
			(effects
				(font
					(size 1 1)
					(thickness 0.15)
				)
				(justify mirror)
			)
		)
		(property "Public" "False"
			(at 0 0 0)
			(layer "B.Fab")
			(hide yes)
			(effects
				(font
					(size 1 1)
					(thickness 0.15)
				)
				(justify mirror)
			)
		)
		(property "Val" "22u"
			(at 0 0 0)
			(layer "B.Fab")
			(hide yes)
			(effects
				(font
					(size 1 1)
					(thickness 0.15)
				)
				(justify mirror)
			)
		)
		(property "Voltage" "16V"
			(at 0 0 0)
			(layer "B.Fab")
			(hide yes)
			(effects
				(font
					(size 1 1)
					(thickness 0.15)
				)
				(justify mirror)
			)
		)
		(sheetname "PCIe misc")
		(sheetfile "pcie_misc.kicad_sch")
		(attr smd)
		(fp_line
			(start 0.15 -0.4)
			(end -0.15 -0.4)
			(stroke
				(width 0.15)
				(type solid)
			)
			(layer "B.SilkS")
		)
		(fp_line
			(start 0.15 0.4)
			(end -0.15 0.4)
			(stroke
				(width 0.15)
				(type solid)
			)
			(layer "B.SilkS")
		)
		(fp_rect
			(start -1.25 0.65)
			(end 1.25 -0.65)
			(stroke
				(width 0.05)
				(type solid)
			)
			(fill no)
			(layer "B.CrtYd")
		)
		(fp_rect
			(start -0.8 0.4)
			(end 0.8 -0.4)
			(stroke
				(width 0.15)
				(type solid)
			)
			(fill no)
			(layer "B.Fab")
		)
		(pad "1" smd roundrect
			(at -0.7 0)
			(size 0.8 1)
			(layers "B.Cu" "B.Mask" "B.Paste")
			(roundrect_rratio 0.2)
			(net 1 "GND")
			(pintype "passive")
			(teardrops
				(best_length_ratio 0.2)
				(max_length 1)
				(best_width_ratio 0.9)
				(max_width 2)
				(curved_edges yes)
				(filter_ratio 0.9)
				(enabled yes)
				(allow_two_segments yes)
				(prefer_zone_connections yes)
			)
		)
		(pad "2" smd roundrect
			(at 0.7 0)
			(size 0.8 1)
			(layers "B.Cu" "B.Mask" "B.Paste")
			(roundrect_rratio 0.2)
			(net 2 "+3V3")
			(pintype "passive")
			(teardrops
				(best_length_ratio 0.2)
				(max_length 1)
				(best_width_ratio 0.9)
				(max_width 2)
				(curved_edges yes)
				(filter_ratio 0.9)
				(enabled yes)
				(allow_two_segments yes)
				(prefer_zone_connections yes)
			)
		)
	)
	(footprint "antmicro-footprints:Amphenol_G14A421211112HR"
		(layer "B.Cu")
		(at 98.16 162.355 90)
		(property "Reference" "J4"
			(at 8.5 -1.885 0)
			(unlocked yes)
			(layer "B.SilkS")
			(effects
				(font
					(size 0.7 0.7)
					(thickness 0.15)
				)
				(justify left bottom mirror)
			)
		)
		(property "Value" "OCuLink_x4_Amphenol_G14A421211112HR"
			(at 0 -6.385 270)
			(unlocked yes)
			(layer "B.Fab")
			(effects
				(font
					(size 0.7 0.7)
					(thickness 0.15)
				)
				(justify left bottom mirror)
			)
		)
		(property "Datasheet" "https://cdn.amphenol-cs.com/media/wysiwyg/files/drawing/g14a421x1bxxxhr.pdf"
			(at 0 0 90)
			(layer "F.Fab")
			(hide yes)
			(effects
				(font
					(size 1.27 1.27)
					(thickness 0.15)
				)
			)
		)
		(property "Author" "Antmicro"
			(at 260.515 64.195 0)
			(layer "B.Fab")
			(hide yes)
			(effects
				(font
					(size 1 1)
					(thickness 0.15)
				)
				(justify mirror)
			)
		)
		(property "License" "Apache-2.0"
			(at 260.515 64.195 0)
			(layer "B.Fab")
			(hide yes)
			(effects
				(font
					(size 1 1)
					(thickness 0.15)
				)
				(justify mirror)
			)
		)
		(property "MPN" "G14A421211112HR"
			(at 260.515 64.195 0)
			(layer "B.Fab")
			(hide yes)
			(effects
				(font
					(size 1 1)
					(thickness 0.15)
				)
				(justify mirror)
			)
		)
		(property "Manufacturer" "Amphenol"
			(at 260.515 64.195 0)
			(layer "B.Fab")
			(hide yes)
			(effects
				(font
					(size 1 1)
					(thickness 0.15)
				)
				(justify mirror)
			)
		)
		(sheetname "OCuLink")
		(sheetfile "oculink.kicad_sch")
		(solder_paste_margin -0.06)
		(attr smd)
		(fp_line
			(start 6.8 0.4)
			(end 6.8 3)
			(stroke
				(width 0.1)
				(type default)
			)
			(layer "B.SilkS")
		)
		(fp_line
			(start -6.8 3)
			(end -6.8 0.4)
			(stroke
				(width 0.1)
				(type default)
			)
			(layer "B.SilkS")
		)
		(fp_circle
			(center -5.3 5.52)
			(end -5.25 5.52)
			(stroke
				(width 0.15)
				(type solid)
			)
			(fill yes)
			(layer "B.SilkS")
		)
		(fp_rect
			(start -8.22 5.22)
			(end 8.22 -4.94)
			(stroke
				(width 0.05)
				(type solid)
			)
			(fill no)
			(layer "B.CrtYd")
		)
		(fp_line
			(start -7 -3.065)
			(end 7 -3.065)
			(stroke
				(width 0.1)
				(type default)
			)
			(layer "B.Fab")
		)
		(fp_text user "PCB EDGE"
			(at 2.8 -2.95 270)
			(unlocked yes)
			(layer "B.Fab")
			(effects
				(font
					(size 0.5 0.5)
					(thickness 0.125)
				)
				(justify left bottom mirror)
			)
		)
		(pad "" np_thru_hole circle
			(at -5.42 1.395 180)
			(size 0.95 0.91)
			(drill 0.95)
			(layers "F&B.Cu" "*.Mask")
		)
		(pad "" np_thru_hole circle
			(at 5.95 1.395)
			(size 0.95 1)
			(drill 0.95)
			(layers "F&B.Cu" "*.Mask")
		)
		(pad "A1" smd roundrect
			(at -4.75 2.115)
			(size 0.875 0.3)
			(layers "B.Cu" "B.Mask" "B.Paste")
			(roundrect_rratio 0.5)
			(chamfer_ratio 0.5)
			(chamfer bottom_left)
			(net 60 "/OCuLink/V_{ACT_RX}0")
			(pinfunction "V_{ACT}_RX_3V3")
			(pintype "power_in")
		)
		(pad "A2" smd roundrect
			(at -4.25 2.115)
			(size 0.91 0.31)
			(layers "B.Cu" "B.Mask" "B.Paste")
			(roundrect_rratio 0.5)
			(net 1 "GND")
			(pinfunction "GND")
			(pintype "passive")
		)
		(pad "A3" smd roundrect
			(at -3.75 2.115)
			(size 0.91 0.31)
			(layers "B.Cu" "B.Mask" "B.Paste")
			(roundrect_rratio 0.5)
			(net 186 "/OCuLink/PCIe_{x4}.RX0+")
			(pinfunction "PER0+")
			(pintype "output")
		)
		(pad "A4" smd roundrect
			(at -3.25 2.115)
			(size 0.91 0.31)
			(layers "B.Cu" "B.Mask" "B.Paste")
			(roundrect_rratio 0.5)
			(net 187 "/OCuLink/PCIe_{x4}.RX0-")
			(pinfunction "PER0-")
			(pintype "output")
		)
		(pad "A5" smd roundrect
			(at -2.75 2.115)
			(size 0.91 0.31)
			(layers "B.Cu" "B.Mask" "B.Paste")
			(roundrect_rratio 0.5)
			(net 1 "GND")
			(pinfunction "GND")
			(pintype "passive")
		)
		(pad "A6" smd roundrect
			(at -2.25 2.115)
			(size 0.91 0.31)
			(layers "B.Cu" "B.Mask" "B.Paste")
			(roundrect_rratio 0.5)
			(net 188 "/OCuLink/PCIe_{x4}.RX1+")
			(pinfunction "PER1+")
			(pintype "output")
		)
		(pad "A7" smd roundrect
			(at -1.75 2.115)
			(size 0.91 0.31)
			(layers "B.Cu" "B.Mask" "B.Paste")
			(roundrect_rratio 0.5)
			(net 189 "/OCuLink/PCIe_{x4}.RX1-")
			(pinfunction "PER1-")
			(pintype "output")
		)
		(pad "A8" smd roundrect
			(at -1.25 2.115)
			(size 0.91 0.31)
			(layers "B.Cu" "B.Mask" "B.Paste")
			(roundrect_rratio 0.5)
			(net 1 "GND")
			(pinfunction "GND")
			(pintype "passive")
		)
		(pad "A9" smd roundrect
			(at -0.75 2.115)
			(size 0.91 0.31)
			(layers "B.Cu" "B.Mask" "B.Paste")
			(roundrect_rratio 0.5)
			(net 190 "unconnected-(J4-NC-PadA9)")
			(pinfunction "NC")
			(pintype "no_connect")
		)
		(pad "A10" smd roundrect
			(at -0.25 2.115)
			(size 0.91 0.31)
			(layers "B.Cu" "B.Mask" "B.Paste")
			(roundrect_rratio 0.5)
			(net 191 "unconnected-(J4-~{CWAKE}-PadA10)")
			(pinfunction "~{CWAKE}")
			(pintype "bidirectional+no_connect")
		)
		(pad "A11" smd roundrect
			(at 0.25 2.115)
			(size 0.91 0.31)
			(layers "B.Cu" "B.Mask" "B.Paste")
			(roundrect_rratio 0.5)
			(net 1 "GND")
			(pinfunction "GND")
			(pintype "passive")
		)
		(pad "A12" smd roundrect
			(at 0.75 2.115)
			(size 0.91 0.31)
			(layers "B.Cu" "B.Mask" "B.Paste")
			(roundrect_rratio 0.5)
			(net 192 "/OCuLink/PCIe_{REF0}.CK+")
			(pinfunction "VSP1")
			(pintype "bidirectional")
		)
		(pad "A13" smd roundrect
			(at 1.25 2.115)
			(size 0.91 0.31)
			(layers "B.Cu" "B.Mask" "B.Paste")
			(roundrect_rratio 0.5)
			(net 193 "/OCuLink/PCIe_{REF0}.CK-")
			(pinfunction "VSP2")
			(pintype "bidirectional")
		)
		(pad "A14" smd roundrect
			(at 1.75 2.115)
			(size 0.91 0.31)
			(layers "B.Cu" "B.Mask" "B.Paste")
			(roundrect_rratio 0.5)
			(net 1 "GND")
			(pinfunction "GND")
			(pintype "passive")
		)
		(pad "A15" smd roundrect
			(at 2.25 2.115)
			(size 0.91 0.31)
			(layers "B.Cu" "B.Mask" "B.Paste")
			(roundrect_rratio 0.5)
			(net 194 "/OCuLink/PCIe_{x4}.RX2+")
			(pinfunction "PER2+")
			(pintype "output")
		)
		(pad "A16" smd roundrect
			(at 2.75 2.115)
			(size 0.91 0.31)
			(layers "B.Cu" "B.Mask" "B.Paste")
			(roundrect_rratio 0.5)
			(net 195 "/OCuLink/PCIe_{x4}.RX2-")
			(pinfunction "PER2-")
			(pintype "output")
		)
		(pad "A17" smd roundrect
			(at 3.25 2.115)
			(size 0.91 0.31)
			(layers "B.Cu" "B.Mask" "B.Paste")
			(roundrect_rratio 0.5)
			(net 1 "GND")
			(pinfunction "GND")
			(pintype "passive")
		)
		(pad "A18" smd roundrect
			(at 3.75 2.115)
			(size 0.91 0.31)
			(layers "B.Cu" "B.Mask" "B.Paste")
			(roundrect_rratio 0.5)
			(net 196 "/OCuLink/PCIe_{x4}.RX3+")
			(pinfunction "PER3+")
			(pintype "output")
		)
		(pad "A19" smd roundrect
			(at 4.25 2.115)
			(size 0.91 0.31)
			(layers "B.Cu" "B.Mask" "B.Paste")
			(roundrect_rratio 0.5)
			(net 197 "/OCuLink/PCIe_{x4}.RX3-")
			(pinfunction "PER3-")
			(pintype "output")
		)
		(pad "A20" smd roundrect
			(at 4.75 2.115)
			(size 0.91 0.31)
			(layers "B.Cu" "B.Mask" "B.Paste")
			(roundrect_rratio 0.5)
			(net 1 "GND")
			(pinfunction "GND")
			(pintype "passive")
		)
		(pad "A21" smd roundrect
			(at 5.25 2.115)
			(size 0.91 0.31)
			(layers "B.Cu" "B.Mask" "B.Paste")
			(roundrect_rratio 0.5)
			(chamfer_ratio 0.5)
			(chamfer top_left)
			(net 61 "/OCuLink/5V_CONN0")
			(pinfunction "5V")
			(pintype "passive")
		)
		(pad "B1" smd roundrect
			(at -5.25 4.305)
			(size 0.91 0.31)
			(layers "B.Cu" "B.Mask" "B.Paste")
			(roundrect_rratio 0.5)
			(net 61 "/OCuLink/5V_CONN0")
			(pinfunction "5V")
			(pintype "passive")
		)
		(pad "B2" smd roundrect
			(at -4.75 4.305)
			(size 0.91 0.31)
			(layers "B.Cu" "B.Mask" "B.Paste")
			(roundrect_rratio 0.5)
			(net 1 "GND")
			(pinfunction "GND")
			(pintype "passive")
		)
		(pad "B3" smd roundrect
			(at -4.25 4.305)
			(size 0.91 0.31)
			(layers "B.Cu" "B.Mask" "B.Paste")
			(roundrect_rratio 0.5)
			(net 100 "/OCuLink/PCIe_{x4}.TX0+")
			(pinfunction "PET0+")
			(pintype "input")
		)
		(pad "B4" smd roundrect
			(at -3.75 4.305)
			(size 0.91 0.31)
			(layers "B.Cu" "B.Mask" "B.Paste")
			(roundrect_rratio 0.5)
			(net 95 "/OCuLink/PCIe_{x4}.TX0-")
			(pinfunction "PET0-")
			(pintype "input")
		)
		(pad "B5" smd roundrect
			(at -3.25 4.305)
			(size 0.91 0.31)
			(layers "B.Cu" "B.Mask" "B.Paste")
			(roundrect_rratio 0.5)
			(net 1 "GND")
			(pinfunction "GND")
			(pintype "passive")
		)
		(pad "B6" smd roundrect
			(at -2.75 4.305)
			(size 0.91 0.31)
			(layers "B.Cu" "B.Mask" "B.Paste")
			(roundrect_rratio 0.5)
			(net 102 "/OCuLink/PCIe_{x4}.TX1+")
			(pinfunction "PET1+")
			(pintype "input")
		)
		(pad "B7" smd roundrect
			(at -2.25 4.305)
			(size 0.91 0.31)
			(layers "B.Cu" "B.Mask" "B.Paste")
			(roundrect_rratio 0.5)
			(net 96 "/OCuLink/PCIe_{x4}.TX1-")
			(pinfunction "PET1-")
			(pintype "input")
		)
		(pad "B8" smd roundrect
			(at -1.75 4.305)
			(size 0.91 0.31)
			(layers "B.Cu" "B.Mask" "B.Paste")
			(roundrect_rratio 0.5)
			(net 1 "GND")
			(pinfunction "GND")
			(pintype "passive")
		)
		(pad "B9" smd roundrect
			(at -1.25 4.305)
			(size 0.91 0.31)
			(layers "B.Cu" "B.Mask" "B.Paste")
			(roundrect_rratio 0.5)
			(net 198 "/OCuLink/SCL")
			(pinfunction "SCL")
			(pintype "bidirectional")
		)
		(pad "B10" smd roundrect
			(at -0.75 4.305)
			(size 0.91 0.31)
			(layers "B.Cu" "B.Mask" "B.Paste")
			(roundrect_rratio 0.5)
			(net 199 "/OCuLink/SDA")
			(pinfunction "SDA")
			(pintype "bidirectional")
		)
		(pad "B11" smd roundrect
			(at -0.25 4.305)
			(size 0.91 0.31)
			(layers "B.Cu" "B.Mask" "B.Paste")
			(roundrect_rratio 0.5)
			(net 1 "GND")
			(pinfunction "GND")
			(pintype "passive")
		)
		(pad "B12" smd roundrect
			(at 0.25 4.305)
			(size 0.91 0.31)
			(layers "B.Cu" "B.Mask" "B.Paste")
			(roundrect_rratio 0.5)
			(net 200 "/OCuLink/~{PERST_D0}")
			(pinfunction "~{PERST}")
			(pintype "bidirectional")
		)
		(pad "B13" smd roundrect
			(at 0.75 4.305)
			(size 0.91 0.31)
			(layers "B.Cu" "B.Mask" "B.Paste")
			(roundrect_rratio 0.5)
			(net 201 "/OCuLink/~{CPRSNT_D0}")
			(pinfunction "~{CPRSNT}")
			(pintype "bidirectional")
		)
		(pad "B14" smd roundrect
			(at 1.25 4.305)
			(size 0.91 0.31)
			(layers "B.Cu" "B.Mask" "B.Paste")
			(roundrect_rratio 0.5)
			(net 1 "GND")
			(pinfunction "GND")
			(pintype "passive")
		)
		(pad "B15" smd roundrect
			(at 1.75 4.305)
			(size 0.91 0.31)
			(layers "B.Cu" "B.Mask" "B.Paste")
			(roundrect_rratio 0.5)
			(net 104 "/OCuLink/PCIe_{x4}.TX2+")
			(pinfunction "PET2+")
			(pintype "input")
		)
		(pad "B16" smd roundrect
			(at 2.25 4.305)
			(size 0.91 0.31)
			(layers "B.Cu" "B.Mask" "B.Paste")
			(roundrect_rratio 0.5)
			(net 97 "/OCuLink/PCIe_{x4}.TX2-")
			(pinfunction "PET2-")
			(pintype "input")
		)
		(pad "B17" smd roundrect
			(at 2.75 4.305)
			(size 0.91 0.31)
			(layers "B.Cu" "B.Mask" "B.Paste")
			(roundrect_rratio 0.5)
			(net 1 "GND")
			(pinfunction "GND")
			(pintype "passive")
		)
		(pad "B18" smd roundrect
			(at 3.25 4.305)
			(size 0.91 0.31)
			(layers "B.Cu" "B.Mask" "B.Paste")
			(roundrect_rratio 0.5)
			(net 106 "/OCuLink/PCIe_{x4}.TX3+")
			(pinfunction "PET3+")
			(pintype "input")
		)
		(pad "B19" smd roundrect
			(at 3.75 4.305)
			(size 0.91 0.31)
			(layers "B.Cu" "B.Mask" "B.Paste")
			(roundrect_rratio 0.5)
			(net 98 "/OCuLink/PCIe_{x4}.TX3-")
			(pinfunction "PET3-")
			(pintype "input")
		)
		(pad "B20" smd roundrect
			(at 4.25 4.305)
			(size 0.91 0.31)
			(layers "B.Cu" "B.Mask" "B.Paste")
			(roundrect_rratio 0.5)
			(net 1 "GND")
			(pinfunction "GND")
			(pintype "passive")
		)
		(pad "B21" smd roundrect
			(at 4.75 4.305)
			(size 0.91 0.31)
			(layers "B.Cu" "B.Mask" "B.Paste")
			(roundrect_rratio 0.5)
			(net 59 "/OCuLink/V_{ACT_TX}0")
			(pinfunction "V_{ACT}_TX_3V3")
			(pintype "power_in")
		)
		(pad "SH" smd roundrect
			(at -6.91 -0.805)
			(size 1.81 1.8)
			(layers "B.Cu" "B.Mask" "B.Paste")
			(roundrect_rratio 0.1)
			(net 1 "GND")
			(pinfunction "SH")
			(pintype "passive")
		)
		(pad "SH" smd roundrect
			(at -6.91 3.915)
			(size 1.38 1.81)
			(layers "B.Cu" "B.Mask" "B.Paste")
			(roundrect_rratio 0.1)
			(net 1 "GND")
			(pinfunction "SH")
			(pintype "passive")
		)
		(pad "SH" smd roundrect
			(at 6.91 -0.805)
			(size 1.81 1.8)
			(layers "B.Cu" "B.Mask" "B.Paste")
			(roundrect_rratio 0.1)
			(net 1 "GND")
			(pinfunction "SH")
			(pintype "passive")
		)
		(pad "SH" smd roundrect
			(at 6.91 3.915)
			(size 1.38 1.81)
			(layers "B.Cu" "B.Mask" "B.Paste")
			(roundrect_rratio 0.1)
			(net 1 "GND")
			(pinfunction "SH")
			(pintype "passive")
		)
	)
)
